# T6G (Grand Teton) — schematic netlist excerpt (pin names and nets, part order shuffled) for the footprints in the layout excerpt that follows; sources: Cadence DE-HDL packaged netlist, KiCad conversion of 04192023_DAF0TMB3IC0_F0TG_MB_C_brd_V02_OCP.brd

PR445  Q_RES  0 5% CHIP  pkg 0402LF  page 194 : A = PVDDCR_CPU0_P0_PVCC ; B = P5V_AUX
R1097  Q_RES  1K 1% CHIP  pkg 0201LF  page 309 : A = P1V8_CPU0_RT_1D ; B = RT_CPU0_P3_ADDR3
C1278  Q_CAP  0.1UF 25V 10% X7R  pkg 0402  page 145 : A = P12V_E1S_0_R ; B = GND

(kicad_pcb
	(version 20260206)
	(generator "pcbnew")
	(generator_version "10.0")
	(general
		(thickness 1.6)
		(legacy_teardrops no)
	)
	(paper "A4")
	(title_block
		(title "04192023_DAF0TMB3IC0_F0TG_MB_C_brd_V02_OCP.brd")
		(comment 1 "Grand Teton / footprints 3805-3807 of 8354")
	)
	(layers
		(0 "F.Cu" signal "TOP")
		(4 "In1.Cu" signal "GND")
		(6 "In2.Cu" signal "IN1")
		(8 "In3.Cu" signal "GND1")
		(10 "In4.Cu" signal "IN2")
		(12 "In5.Cu" signal "GND2")
		(14 "In6.Cu" signal "IN3")
		(16 "In7.Cu" signal "GND3")
		(18 "In8.Cu" signal "VCC")
		(20 "In9.Cu" signal "VCC1")
		(22 "In10.Cu" signal "GND4")
		(24 "In11.Cu" signal "IN4")
		(26 "In12.Cu" signal "GND5")
		(28 "In13.Cu" signal "IN5")
		(30 "In14.Cu" signal "GND6")
		(32 "In15.Cu" signal "IN6")
		(34 "In16.Cu" signal "GND7")
		(2 "B.Cu" signal "BOTTOM")
		(9 "F.Adhes" user "F.Adhesive")
		(11 "B.Adhes" user "B.Adhesive")
		(13 "F.Paste" user "Package Geometry/Pastemask Top")
		(15 "B.Paste" user "Package Geometry/Pastemask Bottom")
		(5 "F.SilkS" user "Ref Des/Silkscreen Top")
		(7 "B.SilkS" user "Ref Des/Silkscreen Bottom")
		(1 "F.Mask" user "Board Geometry/Soldermask Top")
		(3 "B.Mask" user "Board Geometry/Soldermask Bottom")
		(17 "Dwgs.User" user "User.Drawings")
		(19 "Cmts.User" user "User.Comments")
		(21 "Eco1.User" user "User.Eco1")
		(23 "Eco2.User" user "User.Eco2")
		(25 "Edge.Cuts" user "Board Geometry/Outline")
		(27 "Margin" user)
		(31 "F.CrtYd" user "Package Geometry/Place Bound Top")
		(29 "B.CrtYd" user "Package Geometry/Place Bound Bottom")
		(35 "F.Fab" user "Ref Des/Assembly Top")
		(33 "B.Fab" user "Ref Des/Assembly Bottom")
	)
	(footprint ""
		(layer "F.Cu")
		(at 420.153338 -157.606492 -90)
		(property "Reference" "PR445"
			(at 0 0 270)
			(layer "F.SilkS")
			(hide yes)
			(effects
				(font
					(size 1.27 1.27)
				)
			)
		)
		(property "Value" ""
			(at 0 0 270)
			(layer "F.Fab")
			(effects
				(font
					(size 1.27 1.27)
				)
			)
		)
		(duplicate_pad_numbers_are_jumpers no)
		(fp_line
			(start -0.7874 0.4064)
			(end -0.7874 -0.4064)
			(stroke
				(width 0.1524)
				(type default)
			)
			(layer "F.SilkS")
		)
		(fp_line
			(start 0.7874 0.4064)
			(end -0.7874 0.4064)
			(stroke
				(width 0.1524)
				(type default)
			)
			(layer "F.SilkS")
		)
		(fp_line
			(start -0.7874 -0.4064)
			(end 0.7874 -0.4064)
			(stroke
				(width 0.1524)
				(type default)
			)
			(layer "F.SilkS")
		)
		(fp_line
			(start 0.7874 -0.4064)
			(end 0.7874 0.4064)
			(stroke
				(width 0.1524)
				(type default)
			)
			(layer "F.SilkS")
		)
		(fp_line
			(start -0.67945 0.3048)
			(end -0.67945 -0.305054)
			(stroke
				(width 0.1)
				(type default)
			)
			(layer "F.Fab")
		)
		(fp_line
			(start -0.12065 0.3048)
			(end -0.67945 0.3048)
			(stroke
				(width 0.1)
				(type default)
			)
			(layer "F.Fab")
		)
		(fp_line
			(start 0.120396 0.3048)
			(end 0.120396 0.2794)
			(stroke
				(width 0.1)
				(type default)
			)
			(layer "F.Fab")
		)
		(fp_line
			(start 0.67945 0.3048)
			(end 0.120396 0.3048)
			(stroke
				(width 0.1)
				(type default)
			)
			(layer "F.Fab")
		)
		(fp_line
			(start -0.12065 0.2794)
			(end -0.12065 0.3048)
			(stroke
				(width 0.1)
				(type default)
			)
			(layer "F.Fab")
		)
		(fp_line
			(start 0.120396 0.2794)
			(end -0.12065 0.2794)
			(stroke
				(width 0.1)
				(type default)
			)
			(layer "F.Fab")
		)
		(fp_line
			(start -0.12065 -0.2794)
			(end 0.12065 -0.2794)
			(stroke
				(width 0.1)
				(type default)
			)
			(layer "F.Fab")
		)
		(fp_line
			(start 0.12065 -0.2794)
			(end 0.12065 -0.3048)
			(stroke
				(width 0.1)
				(type default)
			)
			(layer "F.Fab")
		)
		(fp_line
			(start 0.12065 -0.3048)
			(end 0.67945 -0.3048)
			(stroke
				(width 0.1)
				(type default)
			)
			(layer "F.Fab")
		)
		(fp_line
			(start 0.67945 -0.3048)
			(end 0.67945 0.3048)
			(stroke
				(width 0.1)
				(type default)
			)
			(layer "F.Fab")
		)
		(fp_line
			(start -0.67945 -0.305054)
			(end -0.12065 -0.305054)
			(stroke
				(width 0.1)
				(type default)
			)
			(layer "F.Fab")
		)
		(fp_line
			(start -0.12065 -0.305054)
			(end -0.12065 -0.2794)
			(stroke
				(width 0.1)
				(type default)
			)
			(layer "F.Fab")
		)
		(pad "1" smd circle
			(at -0.40005 0 270)
			(size 0 0)
			(layers "F.Cu" "F.Mask" "F.Paste")
			(net "PVDDCR_CPU0_P0_PVCC")
		)
		(pad "2" smd circle
			(at 0.40005 0 270)
			(size 0 0)
			(layers "F.Cu" "F.Mask" "F.Paste")
			(net "P5V_AUX")
		)
	)
	(footprint ""
		(layer "F.Cu")
		(at 394.981938 -393.9032 90)
		(property "Reference" "R1097"
			(at 0 0 90)
			(layer "F.SilkS")
			(hide yes)
			(effects
				(font
					(size 1.27 1.27)
				)
			)
		)
		(property "Value" ""
			(at 0 0 90)
			(layer "F.Fab")
			(effects
				(font
					(size 1.27 1.27)
				)
			)
		)
		(duplicate_pad_numbers_are_jumpers no)
		(fp_line
			(start 0.32512 -0.175006)
			(end 0.32512 0.175006)
			(stroke
				(width 0.1)
				(type default)
			)
			(layer "F.Fab")
		)
		(fp_line
			(start -0.32512 -0.175006)
			(end 0.32512 -0.175006)
			(stroke
				(width 0.1)
				(type default)
			)
			(layer "F.Fab")
		)
		(fp_line
			(start 0.32512 0.175006)
			(end -0.32512 0.175006)
			(stroke
				(width 0.1)
				(type default)
			)
			(layer "F.Fab")
		)
		(fp_line
			(start -0.32512 0.175006)
			(end -0.32512 -0.175006)
			(stroke
				(width 0.1)
				(type default)
			)
			(layer "F.Fab")
		)
		(pad "1" smd rect
			(at -0.2667 0 90)
			(size 0.3048 0.381)
			(layers "F.Cu" "F.Mask" "F.Paste")
			(net "P1V8_CPU0_RT_1D")
		)
		(pad "2" smd rect
			(at 0.2667 0 270)
			(size 0.3048 0.381)
			(layers "F.Cu" "F.Mask" "F.Paste")
			(net "RT_CPU0_P3_ADDR3")
		)
	)
	(footprint ""
		(layer "F.Cu")
		(at 245.222268 -44.03979 90)
		(property "Reference" "C1278"
			(at 0 0 90)
			(layer "F.SilkS")
			(hide yes)
			(effects
				(font
					(size 1.27 1.27)
				)
			)
		)
		(property "Value" ""
			(at 0 0 90)
			(layer "F.Fab")
			(effects
				(font
					(size 1.27 1.27)
				)
			)
		)
		(duplicate_pad_numbers_are_jumpers no)
		(fp_line
			(start 0.7874 -0.4064)
			(end 0.7874 0.4064)
			(stroke
				(width 0.1524)
				(type default)
			)
			(layer "F.SilkS")
		)
		(fp_line
			(start -0.7874 -0.4064)
			(end 0.7874 -0.4064)
			(stroke
				(width 0.1524)
				(type default)
			)
			(layer "F.SilkS")
		)
		(fp_line
			(start 0.7874 0.4064)
			(end -0.7874 0.4064)
			(stroke
				(width 0.1524)
				(type default)
			)
			(layer "F.SilkS")
		)
		(fp_line
			(start -0.7874 0.4064)
			(end -0.7874 -0.4064)
			(stroke
				(width 0.1524)
				(type default)
			)
			(layer "F.SilkS")
		)
		(fp_line
			(start -0.12065 -0.305054)
			(end -0.12065 -0.2794)
			(stroke
				(width 0.1)
				(type default)
			)
			(layer "F.Fab")
		)
		(fp_line
			(start -0.67945 -0.305054)
			(end -0.12065 -0.305054)
			(stroke
				(width 0.1)
				(type default)
			)
			(layer "F.Fab")
		)
		(fp_line
			(start 0.67945 -0.3048)
			(end 0.67945 0.3048)
			(stroke
				(width 0.1)
				(type default)
			)
			(layer "F.Fab")
		)
		(fp_line
			(start 0.12065 -0.3048)
			(end 0.67945 -0.3048)
			(stroke
				(width 0.1)
				(type default)
			)
			(layer "F.Fab")
		)
		(fp_line
			(start 0.12065 -0.2794)
			(end 0.12065 -0.3048)
			(stroke
				(width 0.1)
				(type default)
			)
			(layer "F.Fab")
		)
		(fp_line
			(start -0.12065 -0.2794)
			(end 0.12065 -0.2794)
			(stroke
				(width 0.1)
				(type default)
			)
			(layer "F.Fab")
		)
		(fp_line
			(start 0.120396 0.2794)
			(end -0.12065 0.2794)
			(stroke
				(width 0.1)
				(type default)
			)
			(layer "F.Fab")
		)
		(fp_line
			(start -0.12065 0.2794)
			(end -0.12065 0.3048)
			(stroke
				(width 0.1)
				(type default)
			)
			(layer "F.Fab")
		)
		(fp_line
			(start 0.67945 0.3048)
			(end 0.120396 0.3048)
			(stroke
				(width 0.1)
				(type default)
			)
			(layer "F.Fab")
		)
		(fp_line
			(start 0.120396 0.3048)
			(end 0.120396 0.2794)
			(stroke
				(width 0.1)
				(type default)
			)
			(layer "F.Fab")
		)
		(fp_line
			(start -0.12065 0.3048)
			(end -0.67945 0.3048)
			(stroke
				(width 0.1)
				(type default)
			)
			(layer "F.Fab")
		)
		(fp_line
			(start -0.67945 0.3048)
			(end -0.67945 -0.305054)
			(stroke
				(width 0.1)
				(type default)
			)
			(layer "F.Fab")
		)
		(pad "1" smd circle
			(at -0.40005 0 90)
			(size 0 0)
			(layers "F.Cu" "F.Mask" "F.Paste")
			(net "P12V_E1S_0_R")
		)
		(pad "2" smd circle
			(at 0.40005 0 90)
			(size 0 0)
			(layers "F.Cu" "F.Mask" "F.Paste")
			(net "GND")
		)
	)
)
